(kicad_pcb
	(version 20260206)
	(generator "pcbnew")
	(generator_version "10.0")
	(general
		(thickness 1.6)
		(legacy_teardrops no)
	)
	(paper "A4")
	(title_block
		(title "timecard-production-celestica-r4006 — R4006-B0001-02_R01.brd")
		(comment 1 "Time Appliance Project (Time Card) / footprints 799-802 of 1113")
	)
	(layers
		(0 "F.Cu" signal "TOP")
		(4 "In1.Cu" signal "L02_GND1")
		(6 "In2.Cu" signal "L03_SIG1")
		(8 "In3.Cu" signal "L04_GND2")
		(10 "In4.Cu" signal "L05_VCC1")
		(12 "In5.Cu" signal "L06_VCC2")
		(14 "In6.Cu" signal "L07_GND3")
		(16 "In7.Cu" signal "L08_SIG2")
		(18 "In8.Cu" signal "L09_GND4")
		(2 "B.Cu" signal "BOTTOM")
		(9 "F.Adhes" user "F.Adhesive")
		(11 "B.Adhes" user "B.Adhesive")
		(13 "F.Paste" user "Package Geometry/Pastemask Top")
		(15 "B.Paste" user "Package Geometry/Pastemask Bottom")
		(5 "F.SilkS" user "Ref Des/Silkscreen Top")
		(7 "B.SilkS" user "Ref Des/Silkscreen Bottom")
		(1 "F.Mask" user "Board Geometry/Soldermask Top")
		(3 "B.Mask" user "Board Geometry/Soldermask Bottom")
		(17 "Dwgs.User" user "User.Drawings")
		(19 "Cmts.User" user "User.Comments")
		(21 "Eco1.User" user "User.Eco1")
		(23 "Eco2.User" user "User.Eco2")
		(25 "Edge.Cuts" user "Board Geometry/Outline")
		(27 "Margin" user)
		(31 "F.CrtYd" user "Package Geometry/Place Bound Top")
		(29 "B.CrtYd" user "Package Geometry/Place Bound Bottom")
		(35 "F.Fab" user "Ref Des/Assembly Top")
		(33 "B.Fab" user "Ref Des/Assembly Bottom")
	)
	(footprint ""
		(layer "B.Cu")
		(at 76.454 -55.372 90)
		(property "Reference" "Q2"
			(at 0 3.77063 270)
			(unlocked yes)
			(layer "B.SilkS")
			(effects
				(font
					(size 0.7874 0.5842)
					(thickness 0.1524)
				)
				(justify mirror)
			)
		)
		(property "Value" ""
			(at 0 0 90)
			(layer "B.Fab")
			(effects
				(font
					(size 1.27 1.27)
				)
				(justify mirror)
			)
		)
		(property "User Part Number" "PARTNUM*"
			(at 0.074676 4.841748 90)
			(unlocked yes)
			(layer "Cmts.User")
			(hide yes)
			(effects
				(font
					(size 0.7874 0.5842)
					(thickness 0.000001)
				)
				(justify mirror)
			)
		)
		(property "Device Type" "POWERMOS_3P_NCH_V1-G121-10200-A"
			(at 0.051562 3.91414 90)
			(unlocked yes)
			(layer "B.Fab")
			(hide yes)
			(effects
				(font
					(size 0.7874 0.5842)
					(thickness 0.000001)
				)
				(justify mirror)
			)
		)
		(duplicate_pad_numbers_are_jumpers no)
		(fp_line
			(start 0.7493 -2.0574)
			(end -0.7493 -2.0574)
			(stroke
				(width 0.1)
				(type default)
			)
			(layer "B.SilkS")
		)
		(fp_line
			(start -0.7493 -2.0574)
			(end -0.7493 -0.9144)
			(stroke
				(width 0.1)
				(type default)
			)
			(layer "B.SilkS")
		)
		(fp_line
			(start 1.7018 -0.9144)
			(end 0.7493 -0.9144)
			(stroke
				(width 0.1)
				(type default)
			)
			(layer "B.SilkS")
		)
		(fp_line
			(start 0.7493 -0.9144)
			(end 0.7493 -2.0574)
			(stroke
				(width 0.1)
				(type default)
			)
			(layer "B.SilkS")
		)
		(fp_line
			(start -0.7493 -0.9144)
			(end -1.7018 -0.9144)
			(stroke
				(width 0.1)
				(type default)
			)
			(layer "B.SilkS")
		)
		(fp_line
			(start -1.7018 -0.9144)
			(end -1.7018 2.0574)
			(stroke
				(width 0.1)
				(type default)
			)
			(layer "B.SilkS")
		)
		(fp_line
			(start 0.1905 0.9144)
			(end 0.1905 2.0574)
			(stroke
				(width 0.1)
				(type default)
			)
			(layer "B.SilkS")
		)
		(fp_line
			(start -0.1905 0.9144)
			(end 0.1905 0.9144)
			(stroke
				(width 0.1)
				(type default)
			)
			(layer "B.SilkS")
		)
		(fp_line
			(start 1.7018 2.0574)
			(end 1.7018 -0.9144)
			(stroke
				(width 0.1)
				(type default)
			)
			(layer "B.SilkS")
		)
		(fp_line
			(start 0.1905 2.0574)
			(end 1.7018 2.0574)
			(stroke
				(width 0.1)
				(type default)
			)
			(layer "B.SilkS")
		)
		(fp_line
			(start -0.1905 2.0574)
			(end -0.1905 0.9144)
			(stroke
				(width 0.1)
				(type default)
			)
			(layer "B.SilkS")
		)
		(fp_line
			(start -1.7018 2.0574)
			(end -0.1905 2.0574)
			(stroke
				(width 0.1)
				(type default)
			)
			(layer "B.SilkS")
		)
		(fp_poly
			(pts
				(arc
					(start 1.27 2.921)
					(mid 1.27 2.159)
					(end 1.27 2.921)
				)
			)
			(stroke
				(width 0)
				(type default)
			)
			(fill yes)
			(layer "B.SilkS")
		)
		(fp_poly
			(pts
				(xy 1.7018 2.0828) (xy 1.7018 -0.9144) (xy 0.762 -0.9144) (xy 0.762 -2.0574) (xy -0.762 -2.0574)
				(xy -0.762 -0.9144) (xy -1.7018 -0.9144) (xy -1.7018 2.0828)
			)
			(stroke
				(width 0)
				(type default)
			)
			(fill no)
			(layer "B.CrtYd")
		)
		(fp_line
			(start 0.2286 -1.143)
			(end -0.2286 -1.143)
			(stroke
				(width 0.1)
				(type default)
			)
			(layer "B.Fab")
		)
		(fp_line
			(start -0.2286 -1.143)
			(end -0.2286 -0.6604)
			(stroke
				(width 0.1)
				(type default)
			)
			(layer "B.Fab")
		)
		(fp_line
			(start 0.2286 -0.9144)
			(end -0.2286 -0.9144)
			(stroke
				(width 0.1)
				(type default)
			)
			(layer "B.Fab")
		)
		(fp_line
			(start 1.4478 -0.6604)
			(end -1.4478 -0.6604)
			(stroke
				(width 0.1)
				(type default)
			)
			(layer "B.Fab")
		)
		(fp_line
			(start 1.4478 -0.6604)
			(end 1.3716 -0.5842)
			(stroke
				(width 0.1)
				(type default)
			)
			(layer "B.Fab")
		)
		(fp_line
			(start 0.2286 -0.6604)
			(end 0.2286 -1.143)
			(stroke
				(width 0.1)
				(type default)
			)
			(layer "B.Fab")
		)
		(fp_line
			(start -0.2286 -0.6604)
			(end 0.2286 -0.6604)
			(stroke
				(width 0.1)
				(type default)
			)
			(layer "B.Fab")
		)
		(fp_line
			(start -1.4478 -0.6604)
			(end -1.4478 0.6604)
			(stroke
				(width 0.1)
				(type default)
			)
			(layer "B.Fab")
		)
		(fp_line
			(start 1.3716 -0.5842)
			(end -1.3716 -0.5842)
			(stroke
				(width 0.1)
				(type default)
			)
			(layer "B.Fab")
		)
		(fp_line
			(start -1.3716 -0.5842)
			(end -1.4478 -0.6604)
			(stroke
				(width 0.1)
				(type default)
			)
			(layer "B.Fab")
		)
		(fp_line
			(start -1.3716 -0.5842)
			(end -1.3716 0.5842)
			(stroke
				(width 0.1)
				(type default)
			)
			(layer "B.Fab")
		)
		(fp_line
			(start 1.3716 0.5842)
			(end 1.3716 -0.5842)
			(stroke
				(width 0.1)
				(type default)
			)
			(layer "B.Fab")
		)
		(fp_line
			(start -1.3716 0.5842)
			(end 1.3716 0.5842)
			(stroke
				(width 0.1)
				(type default)
			)
			(layer "B.Fab")
		)
		(fp_line
			(start -1.3716 0.5842)
			(end -1.4478 0.6604)
			(stroke
				(width 0.1)
				(type default)
			)
			(layer "B.Fab")
		)
		(fp_line
			(start 1.4478 0.6604)
			(end 1.4478 -0.6604)
			(stroke
				(width 0.1)
				(type default)
			)
			(layer "B.Fab")
		)
		(fp_line
			(start 1.4478 0.6604)
			(end 1.3716 0.5842)
			(stroke
				(width 0.1)
				(type default)
			)
			(layer "B.Fab")
		)
		(fp_line
			(start 1.1684 0.6604)
			(end 0.7112 0.6604)
			(stroke
				(width 0.1)
				(type default)
			)
			(layer "B.Fab")
		)
		(fp_line
			(start 0.7112 0.6604)
			(end 0.7112 1.143)
			(stroke
				(width 0.1)
				(type default)
			)
			(layer "B.Fab")
		)
		(fp_line
			(start -0.7112 0.6604)
			(end -1.1684 0.6604)
			(stroke
				(width 0.1)
				(type default)
			)
			(layer "B.Fab")
		)
		(fp_line
			(start -1.1684 0.6604)
			(end -1.1684 1.143)
			(stroke
				(width 0.1)
				(type default)
			)
			(layer "B.Fab")
		)
		(fp_line
			(start -1.4478 0.6604)
			(end 1.4478 0.6604)
			(stroke
				(width 0.1)
				(type default)
			)
			(layer "B.Fab")
		)
		(fp_line
			(start 1.1684 0.9144)
			(end 0.7112 0.9144)
			(stroke
				(width 0.1)
				(type default)
			)
			(layer "B.Fab")
		)
		(fp_line
			(start -0.7112 0.9144)
			(end -1.1684 0.9144)
			(stroke
				(width 0.1)
				(type default)
			)
			(layer "B.Fab")
		)
		(fp_line
			(start 1.1684 1.143)
			(end 1.1684 0.6604)
			(stroke
				(width 0.1)
				(type default)
			)
			(layer "B.Fab")
		)
		(fp_line
			(start 0.7112 1.143)
			(end 1.1684 1.143)
			(stroke
				(width 0.1)
				(type default)
			)
			(layer "B.Fab")
		)
		(fp_line
			(start -0.7112 1.143)
			(end -0.7112 0.6604)
			(stroke
				(width 0.1)
				(type default)
			)
			(layer "B.Fab")
		)
		(fp_line
			(start -1.1684 1.143)
			(end -0.7112 1.143)
			(stroke
				(width 0.1)
				(type default)
			)
			(layer "B.Fab")
		)
		(fp_poly
			(pts
				(arc
					(start 1.016 2.794)
					(mid 1.016 2.032)
					(end 1.016 2.794)
				)
			)
			(stroke
				(width 0)
				(type default)
			)
			(fill yes)
			(layer "B.Fab")
		)
		(fp_text user "2"
			(at -1.42875 2.667 0)
			(unlocked yes)
			(layer "B.SilkS")
			(effects
				(font
					(size 0.635 0.4064)
					(thickness 0.1524)
				)
				(justify mirror)
			)
		)
		(fp_text user "2"
			(at -1.05537 2.54 0)
			(unlocked yes)
			(layer "B.Fab")
			(effects
				(font
					(size 0.7874 0.5842)
					(thickness 0.1524)
				)
				(justify mirror)
			)
		)
		(pad "1" smd rect
			(at 0.9398 1.1049 270)
			(size 0.9906 1.397)
			(layers "B.Cu" "B.Mask" "B.Paste")
			(net "USB_PWR_EN")
		)
		(pad "2" smd rect
			(at -0.9398 1.1049 270)
			(size 0.9906 1.397)
			(layers "B.Cu" "B.Mask" "B.Paste")
			(net "SG")
		)
		(pad "3" smd rect
			(at 0 -1.1049 270)
			(size 0.9906 1.397)
			(layers "B.Cu" "B.Mask" "B.Paste")
			(net "UNNAMED_527_POWERMOS3PNCHV1_I23")
		)
	)
	(footprint ""
		(layer "B.Cu")
		(at 82.423 -73.152 90)
		(property "Reference" "C62"
			(at -0.508 1.23063 270)
			(unlocked yes)
			(layer "B.SilkS")
			(effects
				(font
					(size 0.7874 0.5842)
					(thickness 0.1524)
				)
				(justify mirror)
			)
		)
		(property "Value" "VAL*"
			(at -0.0762 2.067306 90)
			(unlocked yes)
			(layer "B.Fab")
			(hide yes)
			(effects
				(font
					(size 0.7874 0.5842)
					(thickness 0.1524)
				)
				(justify mirror)
			)
		)
		(property "Tolerance" "TOL*"
			(at -0.0762 3.032506 90)
			(unlocked yes)
			(layer "Cmts.User")
			(hide yes)
			(effects
				(font
					(size 0.7874 0.5842)
					(thickness 0.1524)
				)
				(justify mirror)
			)
		)
		(property "User Part Number" "PARTNUM*"
			(at -0.1016 4.023106 90)
			(unlocked yes)
			(layer "Cmts.User")
			(hide yes)
			(effects
				(font
					(size 0.7874 0.5842)
					(thickness 0.1524)
				)
				(justify mirror)
			)
		)
		(property "Device Type" "CAPACITOR-G105-0B104-EK,0.1UF,A"
			(at -0.0508 1.127506 90)
			(unlocked yes)
			(layer "B.Fab")
			(hide yes)
			(effects
				(font
					(size 0.7874 0.5842)
					(thickness 0.1524)
				)
				(justify mirror)
			)
		)
		(duplicate_pad_numbers_are_jumpers no)
		(fp_line
			(start 1.143 -0.5588)
			(end 1.143 0.5588)
			(stroke
				(width 0.1)
				(type default)
			)
			(layer "B.SilkS")
		)
		(fp_line
			(start -1.143 -0.5588)
			(end 1.143 -0.5588)
			(stroke
				(width 0.1)
				(type default)
			)
			(layer "B.SilkS")
		)
		(fp_line
			(start 1.143 0.5588)
			(end -1.143 0.5588)
			(stroke
				(width 0.1)
				(type default)
			)
			(layer "B.SilkS")
		)
		(fp_line
			(start -1.143 0.5588)
			(end -1.143 -0.5588)
			(stroke
				(width 0.1)
				(type default)
			)
			(layer "B.SilkS")
		)
		(fp_rect
			(start -1.143 -0.5588)
			(end 1.143 0.5588)
			(stroke
				(width 0)
				(type default)
			)
			(fill no)
			(layer "B.CrtYd")
		)
		(fp_line
			(start 0.508 -0.3048)
			(end 0.508 0.3048)
			(stroke
				(width 0.1)
				(type default)
			)
			(layer "B.Fab")
		)
		(fp_line
			(start -0.508 -0.3048)
			(end 0.508 -0.3048)
			(stroke
				(width 0.1)
				(type default)
			)
			(layer "B.Fab")
		)
		(fp_line
			(start 0.508 0.3048)
			(end -0.508 0.3048)
			(stroke
				(width 0.1)
				(type default)
			)
			(layer "B.Fab")
		)
		(fp_line
			(start -0.508 0.3048)
			(end -0.508 -0.3048)
			(stroke
				(width 0.1)
				(type default)
			)
			(layer "B.Fab")
		)
		(pad "1" smd rect
			(at 0.5334 0 270)
			(size 0.7112 0.6096)
			(layers "B.Cu" "B.Mask" "B.Paste")
			(net "XP5R0V")
		)
		(pad "2" smd rect
			(at -0.5334 0 270)
			(size 0.7112 0.6096)
			(layers "B.Cu" "B.Mask" "B.Paste")
			(net "SG")
		)
		(zone
			(layer "B.Cu")
			(hatch none 0.5)
			(connect_pads
				(clearance 0)
			)
			(min_thickness 0.25)
			(keepout
				(tracks allowed)
				(vias not_allowed)
				(pads allowed)
				(copperpour not_allowed)
				(footprints allowed)
			)
			(placement
				(enabled no)
				(sheetname "")
			)
			(fill
				(thermal_gap 0.5)
				(thermal_bridge_width 0.5)
				(island_removal_mode 0)
			)
			(polygon
				(pts
					(xy 82.1182 -73.0758) (xy 82.7278 -73.0758) (xy 82.7278 -73.2282) (xy 82.1182 -73.2282)
				)
			)
		)
	)
	(footprint ""
		(layer "B.Cu")
		(at 151.892 -44.704 90)
		(property "Reference" "R434"
			(at -9.94537 0.635 0)
			(unlocked yes)
			(layer "B.SilkS")
			(effects
				(font
					(size 0.7874 0.5842)
					(thickness 0.1524)
				)
				(justify mirror)
			)
		)
		(property "Value" "VAL*"
			(at -0.02032 2.13233 90)
			(unlocked yes)
			(layer "B.Fab")
			(hide yes)
			(effects
				(font
					(size 0.7874 0.5842)
					(thickness 0.1524)
				)
				(justify mirror)
			)
		)
		(property "Tolerance" "TOL*"
			(at -0.044704 3.05435 90)
			(unlocked yes)
			(layer "Cmts.User")
			(hide yes)
			(effects
				(font
					(size 0.7874 0.5842)
					(thickness 0.1524)
				)
				(justify mirror)
			)
		)
		(property "User Part Number" "PARTNUM*"
			(at -0.02032 4.024884 90)
			(unlocked yes)
			(layer "Cmts.User")
			(hide yes)
			(effects
				(font
					(size 0.7874 0.5842)
					(thickness 0.1524)
				)
				(justify mirror)
			)
		)
		(property "Device Type" "RESISTOR-G155-133R0-01,33OHM,1%"
			(at -0.008382 1.210564 90)
			(unlocked yes)
			(layer "B.Fab")
			(hide yes)
			(effects
				(font
					(size 0.7874 0.5842)
					(thickness 0.1524)
				)
				(justify mirror)
			)
		)
		(duplicate_pad_numbers_are_jumpers no)
		(fp_line
			(start 1.143 -0.5588)
			(end 1.143 0.5588)
			(stroke
				(width 0.1)
				(type default)
			)
			(layer "B.SilkS")
		)
		(fp_line
			(start -1.143 -0.5588)
			(end 1.143 -0.5588)
			(stroke
				(width 0.1)
				(type default)
			)
			(layer "B.SilkS")
		)
		(fp_line
			(start 1.143 0.5588)
			(end -1.143 0.5588)
			(stroke
				(width 0.1)
				(type default)
			)
			(layer "B.SilkS")
		)
		(fp_line
			(start -1.143 0.5588)
			(end -1.143 -0.5588)
			(stroke
				(width 0.1)
				(type default)
			)
			(layer "B.SilkS")
		)
		(fp_poly
			(pts
				(xy 1.143 0.5588) (xy -1.143 0.5588) (xy -1.143 -0.5588) (xy 1.143 -0.5588)
			)
			(stroke
				(width 0)
				(type default)
			)
			(fill no)
			(layer "B.CrtYd")
		)
		(fp_line
			(start 0.508 -0.3048)
			(end 0.508 0.3048)
			(stroke
				(width 0.1)
				(type default)
			)
			(layer "B.Fab")
		)
		(fp_line
			(start -0.508 -0.3048)
			(end 0.508 -0.3048)
			(stroke
				(width 0.1)
				(type default)
			)
			(layer "B.Fab")
		)
		(fp_line
			(start 0.508 0.3048)
			(end -0.508 0.3048)
			(stroke
				(width 0.1)
				(type default)
			)
			(layer "B.Fab")
		)
		(fp_line
			(start -0.508 0.3048)
			(end -0.508 -0.3048)
			(stroke
				(width 0.1)
				(type default)
			)
			(layer "B.Fab")
		)
		(pad "1" smd rect
			(at 0.5334 0 270)
			(size 0.7112 0.6096)
			(layers "B.Cu" "B.Mask" "B.Paste")
			(net "UNNAMED_16_CONNHDR2X6FSSMT_I1_1")
		)
		(pad "2" smd rect
			(at -0.5334 0 270)
			(size 0.7112 0.6096)
			(layers "B.Cu" "B.Mask" "B.Paste")
			(net "FPGA_IO_0")
		)
		(zone
			(layer "B.Cu")
			(hatch none 0.5)
			(connect_pads
				(clearance 0)
			)
			(min_thickness 0.25)
			(keepout
				(tracks allowed)
				(vias not_allowed)
				(pads allowed)
				(copperpour not_allowed)
				(footprints allowed)
			)
			(placement
				(enabled no)
				(sheetname "")
			)
			(fill
				(thermal_gap 0.5)
				(thermal_bridge_width 0.5)
				(island_removal_mode 0)
			)
			(polygon
				(pts
					(xy 152.1968 -44.7802) (xy 151.5872 -44.7802) (xy 151.5872 -44.6278) (xy 152.1968 -44.6278)
				)
			)
		)
		(zone
			(layer "B.Cu")
			(hatch none 0.5)
			(connect_pads
				(clearance 0)
			)
			(min_thickness 0.25)
			(keepout
				(tracks not_allowed)
				(vias allowed)
				(pads allowed)
				(copperpour not_allowed)
				(footprints allowed)
			)
			(placement
				(enabled no)
				(sheetname "")
			)
			(fill
				(thermal_gap 0.5)
				(thermal_bridge_width 0.5)
				(island_removal_mode 0)
			)
			(polygon
				(pts
					(xy 152.1968 -44.7802) (xy 151.5872 -44.7802) (xy 151.5872 -44.6278) (xy 152.1968 -44.6278)
				)
			)
		)
	)
	(footprint ""
		(layer "B.Cu")
		(at 19.304 -61.5442 90)
		(property "Reference" "R315"
			(at -0.381 -3.84937 270)
			(unlocked yes)
			(layer "B.SilkS")
			(effects
				(font
					(size 0.7874 0.5842)
					(thickness 0.1524)
				)
				(justify mirror)
			)
		)
		(property "Value" "VAL*"
			(at -0.02032 2.13233 90)
			(unlocked yes)
			(layer "B.Fab")
			(hide yes)
			(effects
				(font
					(size 0.7874 0.5842)
					(thickness 0.1524)
				)
				(justify mirror)
			)
		)
		(property "Tolerance" "TOL*"
			(at -0.044704 3.05435 90)
			(unlocked yes)
			(layer "Cmts.User")
			(hide yes)
			(effects
				(font
					(size 0.7874 0.5842)
					(thickness 0.1524)
				)
				(justify mirror)
			)
		)
		(property "User Part Number" "PARTNUM*"
			(at -0.02032 4.024884 90)
			(unlocked yes)
			(layer "Cmts.User")
			(hide yes)
			(effects
				(font
					(size 0.7874 0.5842)
					(thickness 0.1524)
				)
				(justify mirror)
			)
		)
		(property "Device Type" "RESISTOR-G155-100R0-J0,0OHM,-"
			(at -0.008382 1.210564 90)
			(unlocked yes)
			(layer "B.Fab")
			(hide yes)
			(effects
				(font
					(size 0.7874 0.5842)
					(thickness 0.1524)
				)
				(justify mirror)
			)
		)
		(duplicate_pad_numbers_are_jumpers no)
		(fp_line
			(start 1.143 -0.5588)
			(end 1.143 0.5588)
			(stroke
				(width 0.1)
				(type default)
			)
			(layer "B.SilkS")
		)
		(fp_line
			(start -1.143 -0.5588)
			(end 1.143 -0.5588)
			(stroke
				(width 0.1)
				(type default)
			)
			(layer "B.SilkS")
		)
		(fp_line
			(start 1.143 0.5588)
			(end -1.143 0.5588)
			(stroke
				(width 0.1)
				(type default)
			)
			(layer "B.SilkS")
		)
		(fp_line
			(start -1.143 0.5588)
			(end -1.143 -0.5588)
			(stroke
				(width 0.1)
				(type default)
			)
			(layer "B.SilkS")
		)
		(fp_poly
			(pts
				(xy 1.143 0.5588) (xy -1.143 0.5588) (xy -1.143 -0.5588) (xy 1.143 -0.5588)
			)
			(stroke
				(width 0)
				(type default)
			)
			(fill no)
			(layer "B.CrtYd")
		)
		(fp_line
			(start 0.508 -0.3048)
			(end 0.508 0.3048)
			(stroke
				(width 0.1)
				(type default)
			)
			(layer "B.Fab")
		)
		(fp_line
			(start -0.508 -0.3048)
			(end 0.508 -0.3048)
			(stroke
				(width 0.1)
				(type default)
			)
			(layer "B.Fab")
		)
		(fp_line
			(start 0.508 0.3048)
			(end -0.508 0.3048)
			(stroke
				(width 0.1)
				(type default)
			)
			(layer "B.Fab")
		)
		(fp_line
			(start -0.508 0.3048)
			(end -0.508 -0.3048)
			(stroke
				(width 0.1)
				(type default)
			)
			(layer "B.Fab")
		)
		(pad "1" smd rect
			(at 0.5334 0 270)
			(size 0.7112 0.6096)
			(layers "B.Cu" "B.Mask" "B.Paste")
			(net "ICP10100_I2C_SCL")
		)
		(pad "2" smd rect
			(at -0.5334 0 270)
			(size 0.7112 0.6096)
			(layers "B.Cu" "B.Mask" "B.Paste")
			(net "BF_ICP10100_I2C_SCL")
		)
		(zone
			(layer "B.Cu")
			(hatch none 0.5)
			(connect_pads
				(clearance 0)
			)
			(min_thickness 0.25)
			(keepout
				(tracks allowed)
				(vias not_allowed)
				(pads allowed)
				(copperpour not_allowed)
				(footprints allowed)
			)
			(placement
				(enabled no)
				(sheetname "")
			)
			(fill
				(thermal_gap 0.5)
				(thermal_bridge_width 0.5)
				(island_removal_mode 0)
			)
			(polygon
				(pts
					(xy 19.6088 -61.6204) (xy 18.9992 -61.6204) (xy 18.9992 -61.468) (xy 19.6088 -61.468)
				)
			)
		)
		(zone
			(layer "B.Cu")
			(hatch none 0.5)
			(connect_pads
				(clearance 0)
			)
			(min_thickness 0.25)
			(keepout
				(tracks not_allowed)
				(vias allowed)
				(pads allowed)
				(copperpour not_allowed)
				(footprints allowed)
			)
			(placement
				(enabled no)
				(sheetname "")
			)
			(fill
				(thermal_gap 0.5)
				(thermal_bridge_width 0.5)
				(island_removal_mode 0)
			)
			(polygon
				(pts
					(xy 19.6088 -61.6204) (xy 18.9992 -61.6204) (xy 18.9992 -61.468) (xy 19.6088 -61.468)
				)
			)
		)
	)
)
